G04 ================== begin FILE IDENTIFICATION RECORD ==================*
G04 Layout Name:  12433-2a.brd*
G04 Film Name:    BSILK*
G04 File Format:  Gerber RS274X*
G04 File Origin:  Cadence Allegro 16.5-S056*
G04 Origin Date:  Fri Dec 11 16:47:32 2015*
G04 *
G04 Layer:  VIA CLASS/FILMMASKBOTTOM*
G04 Layer:  REF DES/ASSEMBLY_BOTTOM*
G04 Layer:  PACKAGE GEOMETRY/SILKSCREEN_BOTTOM*
G04 Layer:  DRAWING FORMAT/LAYER_PCB_STORY*
G04 Layer:  DRAWING FORMAT/LAYER_SILK_B*
G04 Layer:  BOARD GEOMETRY/SILKSCREEN_BOTTOM*
G04 *
G04 Offset:    (0.00 0.00)*
G04 Mirror:    No*
G04 Mode:      Positive*
G04 Rotation:  0*
G04 FullContactRelief:  No*
G04 UndefLineWidth:     6.00*
G04 ================== end FILE IDENTIFICATION RECORD ====================*
%FSLAX35Y35*MOIN*%
%IR0*IPPOS*OFA0.00000B0.00000*MIA0B0*SFA1.00000B1.00000*%
%ADD10C,.032*%
%ADD11C,.02*%
%ADD12C,.012*%
%ADD13C,.006*%
G75*
%LPD*%
G75*
G54D10*
X72500Y1717000D03*
Y1699000D03*
X86500Y1713610D03*
Y1700110D03*
Y1726000D03*
X79000Y1766500D03*
X71500Y1760000D03*
X72500Y1733000D03*
X87000Y1774110D03*
X81000Y1802000D03*
X73000Y1813000D03*
X72500Y1830000D03*
X72000Y1798000D03*
X86500Y1793110D03*
X75500Y1838500D03*
X73000Y1847000D03*
X85100Y1844500D03*
X85700Y1852300D03*
X113024Y1452079D03*
X117122Y1448001D03*
X117195Y1456070D03*
X121338Y1452021D03*
X117024Y1452000D03*
X108500Y1727000D03*
X98500Y1717000D03*
Y1696500D03*
X99000Y1707000D03*
X109500Y1719500D03*
X110000Y1709500D03*
X109500Y1699000D03*
X119500Y1710110D03*
Y1696610D03*
Y1725110D03*
X111500Y1768500D03*
X117500Y1732000D03*
X119500Y1760000D03*
X97500Y1775500D03*
X108268Y1777300D03*
X119500Y1747110D03*
X138000Y1824000D03*
X110500Y1801000D03*
X88500Y1785000D03*
X97500Y1796000D03*
X98000Y1786000D03*
X107768Y1789110D03*
X120000Y1811500D03*
X119500Y1796500D03*
X114000Y1843500D03*
X97000Y1850500D03*
X120500Y1836500D03*
Y1850500D03*
X108500Y1851610D03*
X139000Y1696500D03*
Y1712500D03*
X138500Y1727500D03*
X181500Y1716500D03*
X158500D03*
X167500Y1716000D03*
X182000Y1726000D03*
Y1704000D03*
X168500Y1705000D03*
X158500D03*
X184500Y1696500D03*
X163000Y1697000D03*
X174268Y1697110D03*
X152000D03*
Y1710610D03*
Y1725610D03*
X185000Y1738500D03*
X183600Y1765100D03*
X169000Y1781500D03*
X162500Y1773000D03*
X152500Y1771110D03*
X173268Y1776000D03*
X139000Y1800500D03*
X156500Y1782000D03*
X155500Y1798500D03*
X166500Y1798000D03*
X179000Y1798500D03*
X185500Y1804500D03*
X186000Y1790000D03*
X162000D03*
X172768Y1790110D03*
X152000D03*
X139000Y1851000D03*
X138500Y1839500D03*
X185000Y1852500D03*
X161500D03*
X183100Y1838300D03*
X173000Y1852610D03*
X151500Y1851110D03*
G54D11*
G01X-448201Y-66763D02*
X-480201D01*
G01X-448201Y-82763D02*
Y-162763D01*
G01Y-118263D02*
X752899D01*
G01X-448201Y-162763D02*
X752899D01*
G01X-452201Y-66763D02*
G02I-12000J0D01*
G01X-457351D02*
G02I-6850J0D01*
G01X-464201Y-82763D02*
Y-50763D01*
G01X-448201Y-82763D02*
X752899D01*
G01X-34601D02*
Y-162763D01*
G01X102899Y-82763D02*
Y-162763D01*
G01X217899Y-82763D02*
Y-162763D01*
G01X385399Y-82763D02*
Y-162763D01*
G01X555399Y-82763D02*
Y-162763D01*
G01X752899Y-82763D02*
Y-162763D01*
G01X780899Y-66763D02*
G02I-12000J0D01*
G01X775749D02*
G02I-6850J0D01*
G01X768899Y-82763D02*
Y-50763D01*
G01X784899Y-66763D02*
X752899D01*
G54D12*
G01X-206693Y39370D02*
X-175984D01*
G01X-214567Y200796D02*
Y170088D01*
G01Y467044D02*
Y436336D01*
G01Y734051D02*
Y703343D01*
G01Y1001310D02*
Y970602D01*
G01Y1265223D02*
Y1234515D01*
G01X-214568Y1532547D02*
Y1501839D01*
G01X-214567Y1798926D02*
Y1768218D01*
G01X-175984Y1929134D02*
X-206693D01*
G01X-76772Y7874D02*
Y31496D01*
G01X-76763Y1937008D02*
Y1960889D01*
G01X-7874Y11811D02*
Y42520D01*
G01X0Y11811D02*
Y42520D01*
G01X-7874Y278740D02*
Y309449D01*
G01X0Y278740D02*
Y309449D01*
G01X-7874Y545669D02*
Y576378D01*
G01X0Y545669D02*
Y576378D01*
G01Y862205D02*
Y831496D01*
G01X-7874Y862205D02*
Y831496D01*
G01Y1106299D02*
Y1137008D01*
G01X0Y1106299D02*
Y1137008D01*
G01Y1422835D02*
Y1392126D01*
G01X-7874Y1422835D02*
Y1392126D01*
G01X0Y1689764D02*
Y1659055D01*
G01X-7874Y1689764D02*
Y1659055D01*
G01Y1956693D02*
Y1925984D01*
G01X0Y1956693D02*
Y1925984D01*
G01X68889Y7615D02*
Y31496D01*
G01X116607Y1747835D02*
G03I-20150J0D01*
G01Y1823031D02*
G03I-20150J0D01*
G01X68898Y1960630D02*
Y1937008D01*
G01X168110Y39370D02*
X198819D01*
G01X178937Y1308590D02*
G03I0J20150D01*
G01X181567Y1747835D02*
G03I-20150J0D01*
G01Y1823031D02*
G03I-20150J0D01*
G01X198819Y1929134D02*
X168110D01*
G01X222441Y39370D02*
X253150D01*
G01X206693Y169291D02*
Y200000D01*
G01X214567Y169291D02*
Y200000D01*
G01X206693Y436220D02*
Y466929D01*
G01X214567Y436220D02*
Y466929D01*
G01X206693Y733858D02*
Y703149D01*
G01X214567Y733858D02*
Y703149D01*
G01X206693Y997637D02*
Y966928D01*
G01X214567Y997637D02*
Y966928D01*
G01Y1265355D02*
Y1234646D01*
G01X206693Y1265355D02*
Y1234646D01*
G01X214567Y1532284D02*
Y1501575D01*
G01X206693Y1532284D02*
Y1501575D01*
G01X214567Y1799213D02*
Y1768504D01*
G01X206693Y1799213D02*
Y1768504D01*
G01X253150Y1929134D02*
X222441D01*
G01X352362Y7874D02*
Y31496D01*
G01X352370Y1960889D02*
Y1937008D01*
G01X429134Y11811D02*
Y42520D01*
G01X421260Y11811D02*
Y42520D01*
G01X429134Y278740D02*
Y309449D01*
G01X421260Y278740D02*
Y309449D01*
G01X429134Y545669D02*
Y576378D01*
G01X421260Y545669D02*
Y576378D01*
G01X429134Y862205D02*
Y831496D01*
G01X421260Y862205D02*
Y831496D01*
G01X429134Y1106299D02*
Y1137008D01*
G01X421260Y1106299D02*
Y1137008D01*
G01X429134Y1422835D02*
Y1392126D01*
G01X421260Y1422835D02*
Y1392126D01*
G01X429134Y1689764D02*
Y1659055D01*
G01X421260Y1689764D02*
Y1659055D01*
G01X429134Y1956693D02*
Y1925984D01*
G01X421260Y1956693D02*
Y1925984D01*
G01X498023Y7615D02*
Y31496D01*
G01X498032Y1960630D02*
Y1937008D01*
G01X627953Y39370D02*
X597244D01*
G01X627953Y1929134D02*
X597244D01*
G01X635684Y199210D02*
Y168502D01*
G01X635704Y466313D02*
Y435605D01*
G01X635795Y733708D02*
Y703000D01*
G01X635669Y999693D02*
Y968985D01*
G01X635696Y1264678D02*
Y1233970D01*
G01X635748Y1531930D02*
Y1501222D01*
G01X635827Y1799178D02*
Y1768470D01*
G54D13*
G01X-430254Y-152763D02*
Y-135263D01*
G01X-421958D02*
X-430254Y-146055D01*
G01X-420648Y-152763D02*
X-426543Y-141097D01*
G01X-412973Y-152763D02*
Y-135263D01*
X-402929Y-152763D01*
Y-135263D01*
G01X-390451Y-152763D02*
X-392198Y-152471D01*
X-393726Y-151305D01*
X-395036Y-149555D01*
X-395910Y-147513D01*
X-396346Y-145180D01*
Y-142846D01*
X-395910Y-140513D01*
X-395036Y-138471D01*
X-393726Y-136722D01*
X-392198Y-135555D01*
X-390451Y-135263D01*
X-388705Y-135555D01*
X-387176Y-136722D01*
X-385866Y-138471D01*
X-384992Y-140513D01*
X-384556Y-142846D01*
Y-145180D01*
X-384992Y-147513D01*
X-385866Y-149555D01*
X-387176Y-151305D01*
X-388705Y-152471D01*
X-390451Y-152763D01*
G01X-377536D02*
X-368366Y-135263D01*
G01X-377536D02*
X-368366Y-152763D01*
G01X-362001Y-158596D02*
X-348901D01*
G01X-342099Y-152763D02*
Y-135263D01*
X-333803D01*
G01X-336859Y-143721D02*
X-342099D01*
G01X-325910Y-152763D02*
X-320451Y-135263D01*
X-314992Y-152763D01*
G01X-316958Y-146638D02*
X-323945D01*
G01X-307973Y-152763D02*
Y-135263D01*
X-297929Y-152763D01*
Y-135263D01*
G01X-263148Y-136722D02*
X-264458Y-135846D01*
X-265986Y-135263D01*
X-267733D01*
X-269698Y-136138D01*
X-271226Y-137596D01*
X-272318Y-139347D01*
X-273191Y-142263D01*
X-273410Y-144888D01*
X-272973Y-147513D01*
X-272318Y-149263D01*
X-271008Y-151013D01*
X-269479Y-152180D01*
X-267951Y-152763D01*
X-266423D01*
X-264894Y-152180D01*
X-263584Y-151305D01*
X-262492Y-150139D01*
G01X-250451Y-152763D02*
X-252198Y-152471D01*
X-253726Y-151305D01*
X-255036Y-149555D01*
X-255910Y-147513D01*
X-256346Y-145180D01*
Y-142846D01*
X-255910Y-140513D01*
X-255036Y-138471D01*
X-253726Y-136722D01*
X-252198Y-135555D01*
X-250451Y-135263D01*
X-248705Y-135555D01*
X-247176Y-136722D01*
X-245866Y-138471D01*
X-244992Y-140513D01*
X-244556Y-142846D01*
Y-145180D01*
X-244992Y-147513D01*
X-245866Y-149555D01*
X-247176Y-151305D01*
X-248705Y-152471D01*
X-250451Y-152763D01*
G01X-237973D02*
Y-135263D01*
X-227929Y-152763D01*
Y-135263D01*
G01X-215451D02*
Y-152763D01*
G01X-220473Y-135263D02*
X-210429D01*
G01X-202318Y-152763D02*
Y-135263D01*
X-196859D01*
X-195113Y-136138D01*
X-194021Y-137305D01*
X-193584Y-139638D01*
X-194021Y-141972D01*
X-195331Y-143430D01*
X-196859Y-144305D01*
X-202318D01*
G01X-196859D02*
X-193584Y-152763D01*
G01X-180451D02*
X-182198Y-152471D01*
X-183726Y-151305D01*
X-185036Y-149555D01*
X-185910Y-147513D01*
X-186346Y-145180D01*
Y-142846D01*
X-185910Y-140513D01*
X-185036Y-138471D01*
X-183726Y-136722D01*
X-182198Y-135555D01*
X-180451Y-135263D01*
X-178705Y-135555D01*
X-177176Y-136722D01*
X-175866Y-138471D01*
X-174992Y-140513D01*
X-174556Y-142846D01*
Y-145180D01*
X-174992Y-147513D01*
X-175866Y-149555D01*
X-177176Y-151305D01*
X-178705Y-152471D01*
X-180451Y-152763D01*
G01X-167318Y-135263D02*
Y-152763D01*
X-158584D01*
G01X-126205Y-143430D02*
X-125331Y-142555D01*
X-124676Y-141097D01*
X-124239Y-139054D01*
X-124676Y-137305D01*
X-125549Y-136138D01*
X-127078Y-135263D01*
X-132973D01*
Y-152763D01*
X-125768D01*
X-124239Y-151597D01*
X-123366Y-149846D01*
X-122929Y-147805D01*
X-123366Y-145763D01*
X-124676Y-144013D01*
X-126205Y-143430D01*
X-132973D01*
G01X-110451Y-152763D02*
X-112198Y-152471D01*
X-113726Y-151305D01*
X-115036Y-149555D01*
X-115910Y-147513D01*
X-116346Y-145180D01*
Y-142846D01*
X-115910Y-140513D01*
X-115036Y-138471D01*
X-113726Y-136722D01*
X-112198Y-135555D01*
X-110451Y-135263D01*
X-108705Y-135555D01*
X-107176Y-136722D01*
X-105866Y-138471D01*
X-104992Y-140513D01*
X-104556Y-142846D01*
Y-145180D01*
X-104992Y-147513D01*
X-105866Y-149555D01*
X-107176Y-151305D01*
X-108705Y-152471D01*
X-110451Y-152763D01*
G01X-98410D02*
X-92951Y-135263D01*
X-87492Y-152763D01*
G01X-89458Y-146638D02*
X-96445D01*
G01X-79818Y-152763D02*
Y-135263D01*
X-74359D01*
X-72613Y-136138D01*
X-71521Y-137305D01*
X-71084Y-139638D01*
X-71521Y-141972D01*
X-72831Y-143430D01*
X-74359Y-144305D01*
X-79818D01*
G01X-74359D02*
X-71084Y-152763D01*
G01X-62754D02*
Y-135263D01*
X-58388D01*
X-56641Y-136138D01*
X-55331Y-137305D01*
X-54239Y-139054D01*
X-53366Y-141097D01*
X-53148Y-144013D01*
X-53366Y-146930D01*
X-54239Y-148972D01*
X-55331Y-150722D01*
X-56641Y-151888D01*
X-58388Y-152763D01*
X-62754D01*
G01X-282378Y-107763D02*
Y-90263D01*
X-276701Y-104846D01*
X-271024Y-90263D01*
Y-107763D01*
G01X-259201D02*
X-260511Y-107471D01*
X-261821Y-106305D01*
X-262695Y-104263D01*
X-263131Y-101930D01*
X-262695Y-99596D01*
X-261821Y-97555D01*
X-260511Y-96388D01*
X-259201Y-96097D01*
X-257891Y-96388D01*
X-256581Y-97555D01*
X-255708Y-99596D01*
X-255489Y-101930D01*
X-255708Y-104263D01*
X-256581Y-106305D01*
X-257891Y-107471D01*
X-259201Y-107763D01*
G01X-237771Y-90263D02*
Y-107763D01*
G01Y-105139D02*
X-238644Y-106597D01*
X-239955Y-107471D01*
X-241483Y-107763D01*
X-243229Y-107180D01*
X-244539Y-105722D01*
X-245413Y-103972D01*
X-245631Y-101930D01*
X-245413Y-99888D01*
X-244539Y-98138D01*
X-243229Y-96680D01*
X-241483Y-96097D01*
X-239955Y-96388D01*
X-238863Y-96972D01*
X-237771Y-98138D01*
G01X-227476Y-99888D02*
X-220489D01*
X-221144Y-97846D01*
X-222236Y-96680D01*
X-223764Y-96097D01*
X-225293Y-96388D01*
X-226603Y-97263D01*
X-227476Y-99305D01*
X-227913Y-101055D01*
Y-102805D01*
X-227476Y-104555D01*
X-226384Y-106305D01*
X-225074Y-107471D01*
X-223546Y-107763D01*
X-222018Y-107180D01*
X-220489Y-105430D01*
G01X-206701Y-107763D02*
Y-90263D01*
G01X-14018Y-107763D02*
Y-90263D01*
X-8778D01*
X-7031Y-91138D01*
X-5721Y-93180D01*
X-5284Y-95513D01*
X-5721Y-97846D01*
X-6813Y-99596D01*
X-8778Y-100472D01*
X-14018D01*
G01X12652Y-91722D02*
X11342Y-90846D01*
X9814Y-90263D01*
X8067D01*
X6102Y-91138D01*
X4574Y-92596D01*
X3482Y-94347D01*
X2609Y-97263D01*
X2390Y-99888D01*
X2827Y-102513D01*
X3482Y-104263D01*
X4792Y-106013D01*
X6321Y-107180D01*
X7849Y-107763D01*
X9377D01*
X10906Y-107180D01*
X12216Y-106305D01*
X13308Y-105139D01*
G01X27095Y-98430D02*
X27969Y-97555D01*
X28624Y-96097D01*
X29061Y-94054D01*
X28624Y-92305D01*
X27751Y-91138D01*
X26222Y-90263D01*
X20327D01*
Y-107763D01*
X27532D01*
X29061Y-106597D01*
X29934Y-104846D01*
X30371Y-102805D01*
X29934Y-100763D01*
X28624Y-99013D01*
X27095Y-98430D01*
X20327D01*
G01X36299Y-113596D02*
X49399D01*
G01X55327Y-107763D02*
Y-90263D01*
X65371Y-107763D01*
Y-90263D01*
G01X77849Y-107763D02*
X76102Y-107471D01*
X74574Y-106305D01*
X73264Y-104555D01*
X72390Y-102513D01*
X71954Y-100180D01*
Y-97846D01*
X72390Y-95513D01*
X73264Y-93471D01*
X74574Y-91722D01*
X76102Y-90555D01*
X77849Y-90263D01*
X79595Y-90555D01*
X81124Y-91722D01*
X82434Y-93471D01*
X83308Y-95513D01*
X83744Y-97846D01*
Y-100180D01*
X83308Y-102513D01*
X82434Y-104555D01*
X81124Y-106305D01*
X79595Y-107471D01*
X77849Y-107763D01*
G01X-901Y-152763D02*
Y-135263D01*
X-3521Y-138763D01*
G01Y-152763D02*
X1719D01*
G01X12451Y-138180D02*
X13761Y-136430D01*
X15289Y-135555D01*
X17036Y-135263D01*
X19219Y-135846D01*
X20747Y-137305D01*
X21184Y-139054D01*
X20966Y-140805D01*
X20092Y-142263D01*
X15726Y-145180D01*
X13761Y-147221D01*
X12451Y-150139D01*
X12014Y-152763D01*
X21184D01*
G01X36719D02*
Y-135263D01*
X28640Y-147805D01*
X39558D01*
G01X46796Y-149263D02*
X48105Y-151305D01*
X49852Y-152471D01*
X51817Y-152763D01*
X53564Y-152471D01*
X55311Y-151013D01*
X56402Y-149263D01*
X56621Y-147513D01*
X56184Y-145472D01*
X54656Y-144013D01*
X53127Y-143430D01*
X51162D01*
G01X53127D02*
X54437Y-142555D01*
X55529Y-141097D01*
X55966Y-139347D01*
X55529Y-137596D01*
X54437Y-136138D01*
X52472Y-135263D01*
X50507Y-135555D01*
X48542Y-136722D01*
G01X64296Y-149263D02*
X65605Y-151305D01*
X67352Y-152471D01*
X69317Y-152763D01*
X71064Y-152471D01*
X72811Y-151013D01*
X73902Y-149263D01*
X74121Y-147513D01*
X73684Y-145472D01*
X72156Y-144013D01*
X70627Y-143430D01*
X68662D01*
G01X70627D02*
X71937Y-142555D01*
X73029Y-141097D01*
X73466Y-139347D01*
X73029Y-137596D01*
X71937Y-136138D01*
X69972Y-135263D01*
X68007Y-135555D01*
X66042Y-136722D01*
G01X128690Y-90263D02*
X134149Y-107763D01*
X139608Y-90263D01*
G01X156016Y-107763D02*
X147282D01*
Y-90263D01*
X156016D01*
G01X152522Y-98721D02*
X147282D01*
G01X164782Y-107763D02*
Y-90263D01*
X170241D01*
X171987Y-91138D01*
X173079Y-92305D01*
X173516Y-94638D01*
X173079Y-96972D01*
X171769Y-98430D01*
X170241Y-99305D01*
X164782D01*
G01X170241D02*
X173516Y-107763D01*
G01X186649Y-108346D02*
X186212Y-108055D01*
Y-107471D01*
X186649Y-107180D01*
X187086Y-107471D01*
Y-108055D01*
X186649Y-108346D01*
G01X147501Y-138180D02*
X148811Y-136430D01*
X150339Y-135555D01*
X152086Y-135263D01*
X154269Y-135846D01*
X155797Y-137305D01*
X156234Y-139054D01*
X156016Y-140805D01*
X155142Y-142263D01*
X150776Y-145180D01*
X148811Y-147221D01*
X147501Y-150139D01*
X147064Y-152763D01*
X156234D01*
G01X163690D02*
X169149Y-135263D01*
X174608Y-152763D01*
G01X172642Y-146638D02*
X165655D01*
G01X253482Y-90263D02*
Y-107763D01*
X262216D01*
G01X279279D02*
Y-96097D01*
G01Y-98138D02*
X278406Y-96972D01*
X277095Y-96388D01*
X275567Y-96097D01*
X274039Y-96680D01*
X272729Y-97846D01*
X271855Y-99596D01*
X271419Y-101930D01*
X271855Y-104263D01*
X272729Y-106013D01*
X274039Y-107180D01*
X275567Y-107763D01*
X277095Y-107471D01*
X278406Y-106597D01*
X279279Y-105430D01*
G01X288264Y-113013D02*
X289574Y-113596D01*
X291321Y-113013D01*
X292412Y-111847D01*
X293286Y-110388D01*
X294595Y-105722D01*
X297434Y-96097D01*
G01X290447D02*
X294595Y-105722D01*
G01X307074Y-99888D02*
X314061D01*
X313406Y-97846D01*
X312314Y-96680D01*
X310786Y-96097D01*
X309257Y-96388D01*
X307947Y-97263D01*
X307074Y-99305D01*
X306637Y-101055D01*
Y-102805D01*
X307074Y-104555D01*
X308166Y-106305D01*
X309476Y-107471D01*
X311004Y-107763D01*
X312532Y-107180D01*
X314061Y-105430D01*
G01X324792Y-107763D02*
Y-96097D01*
G01Y-98430D02*
X325884Y-97263D01*
X326976Y-96388D01*
X328504Y-96097D01*
X329595Y-96388D01*
X330906Y-97263D01*
G01X342074Y-105722D02*
X343166Y-106888D01*
X344694Y-107763D01*
X346004D01*
X347314Y-107180D01*
X348187Y-106305D01*
X348624Y-105139D01*
X348406Y-103388D01*
X347532Y-102513D01*
X343602Y-100763D01*
X342729Y-98721D01*
X343166Y-97263D01*
X344039Y-96388D01*
X345349Y-96097D01*
X346659Y-96388D01*
X347969Y-97263D01*
G01X334853Y-143430D02*
X333979Y-142555D01*
X333324Y-141097D01*
X332887Y-139054D01*
X333324Y-137305D01*
X334197Y-136138D01*
X335726Y-135263D01*
X341621D01*
Y-152763D01*
X334416D01*
X332887Y-151597D01*
X332014Y-149846D01*
X331577Y-147805D01*
X332014Y-145763D01*
X333324Y-144013D01*
X334853Y-143430D01*
X341621D01*
G01X323684Y-150430D02*
X321937Y-151888D01*
X319972Y-152763D01*
X318226D01*
X316479Y-151888D01*
X315169Y-150430D01*
X314514Y-148388D01*
X314951Y-146347D01*
X316042Y-144596D01*
X318007Y-143430D01*
X320627Y-142846D01*
X322156Y-141680D01*
X322811Y-139638D01*
X322374Y-137596D01*
X321282Y-136138D01*
X319754Y-135263D01*
X318226D01*
X316697Y-135846D01*
X315387Y-137305D01*
G01X304219Y-135263D02*
X298979D01*
G01X301599D02*
Y-152763D01*
G01X304219D02*
X298979D01*
G01X288466Y-135263D02*
Y-152763D01*
X279732D01*
G01X271402D02*
Y-135263D01*
G01X263106D02*
X271402Y-146055D01*
G01X261796Y-152763D02*
X267691Y-141097D01*
G01X404346Y-107763D02*
Y-90263D01*
X408712D01*
X410459Y-91138D01*
X411769Y-92305D01*
X412861Y-94054D01*
X413734Y-96097D01*
X413952Y-99013D01*
X413734Y-101930D01*
X412861Y-103972D01*
X411769Y-105722D01*
X410459Y-106888D01*
X408712Y-107763D01*
X404346D01*
G01X423374Y-99888D02*
X430361D01*
X429706Y-97846D01*
X428614Y-96680D01*
X427086Y-96097D01*
X425557Y-96388D01*
X424247Y-97263D01*
X423374Y-99305D01*
X422937Y-101055D01*
Y-102805D01*
X423374Y-104555D01*
X424466Y-106305D01*
X425776Y-107471D01*
X427304Y-107763D01*
X428832Y-107180D01*
X430361Y-105430D01*
G01X440874Y-105722D02*
X441966Y-106888D01*
X443494Y-107763D01*
X444804D01*
X446114Y-107180D01*
X446987Y-106305D01*
X447424Y-105139D01*
X447206Y-103388D01*
X446332Y-102513D01*
X442402Y-100763D01*
X441529Y-98721D01*
X441966Y-97263D01*
X442839Y-96388D01*
X444149Y-96097D01*
X445459Y-96388D01*
X446769Y-97263D01*
G01X461649Y-96097D02*
Y-107763D01*
G01Y-91430D02*
X461212Y-91138D01*
Y-90555D01*
X461649Y-90263D01*
X462086Y-90555D01*
Y-91138D01*
X461649Y-91430D01*
G01X476092Y-112138D02*
X477621Y-113305D01*
X479367Y-113596D01*
X480895Y-113305D01*
X482206Y-111847D01*
X483079Y-109805D01*
Y-96097D01*
G01Y-98430D02*
X482206Y-97263D01*
X480895Y-96388D01*
X479367Y-96097D01*
X477621Y-96680D01*
X476529Y-97846D01*
X475655Y-99888D01*
X475219Y-101930D01*
X475437Y-103680D01*
X476311Y-105722D01*
X477621Y-107180D01*
X479367Y-107763D01*
X480677Y-107471D01*
X482206Y-106305D01*
X483079Y-105139D01*
G01X492937Y-107763D02*
Y-96097D01*
G01Y-99013D02*
X493811Y-97555D01*
X495121Y-96388D01*
X496867Y-96097D01*
X498395Y-96388D01*
X499706Y-97555D01*
X500361Y-99596D01*
Y-107763D01*
G01X510874Y-99888D02*
X517861D01*
X517206Y-97846D01*
X516114Y-96680D01*
X514586Y-96097D01*
X513057Y-96388D01*
X511747Y-97263D01*
X510874Y-99305D01*
X510437Y-101055D01*
Y-102805D01*
X510874Y-104555D01*
X511966Y-106305D01*
X513276Y-107471D01*
X514804Y-107763D01*
X516332Y-107180D01*
X517861Y-105430D01*
G01X528592Y-107763D02*
Y-96097D01*
G01Y-98430D02*
X529684Y-97263D01*
X530776Y-96388D01*
X532304Y-96097D01*
X533395Y-96388D01*
X534706Y-97263D01*
G01X429722Y-152763D02*
Y-135263D01*
X435399Y-149846D01*
X441076Y-135263D01*
Y-152763D01*
G01X452899D02*
X451152Y-152471D01*
X449624Y-151305D01*
X448314Y-149555D01*
X447440Y-147513D01*
X447004Y-145180D01*
Y-142846D01*
X447440Y-140513D01*
X448314Y-138471D01*
X449624Y-136722D01*
X451152Y-135555D01*
X452899Y-135263D01*
X454645Y-135555D01*
X456174Y-136722D01*
X457484Y-138471D01*
X458358Y-140513D01*
X458794Y-142846D01*
Y-145180D01*
X458358Y-147513D01*
X457484Y-149555D01*
X456174Y-151305D01*
X454645Y-152471D01*
X452899Y-152763D01*
G01X465814Y-150430D02*
X467561Y-151888D01*
X469526Y-152763D01*
X471272D01*
X473019Y-151888D01*
X474329Y-150430D01*
X474984Y-148388D01*
X474547Y-146347D01*
X473456Y-144596D01*
X471491Y-143430D01*
X468871Y-142846D01*
X467342Y-141680D01*
X466687Y-139638D01*
X467124Y-137596D01*
X468216Y-136138D01*
X469744Y-135263D01*
X471272D01*
X472801Y-135846D01*
X474111Y-137305D01*
G01X483314Y-150430D02*
X485061Y-151888D01*
X487026Y-152763D01*
X488772D01*
X490519Y-151888D01*
X491829Y-150430D01*
X492484Y-148388D01*
X492047Y-146347D01*
X490956Y-144596D01*
X488991Y-143430D01*
X486371Y-142846D01*
X484842Y-141680D01*
X484187Y-139638D01*
X484624Y-137596D01*
X485716Y-136138D01*
X487244Y-135263D01*
X488772D01*
X490301Y-135846D01*
X491611Y-137305D01*
G01X509766Y-152763D02*
X501032D01*
Y-135263D01*
X509766D01*
G01X506272Y-143721D02*
X501032D01*
G01X575349Y-152763D02*
Y-135263D01*
X572729Y-138763D01*
G01Y-152763D02*
X577969D01*
G01X588701Y-138180D02*
X590011Y-136430D01*
X591539Y-135555D01*
X593286Y-135263D01*
X595469Y-135846D01*
X596997Y-137305D01*
X597434Y-139054D01*
X597216Y-140805D01*
X596342Y-142263D01*
X591976Y-145180D01*
X590011Y-147221D01*
X588701Y-150139D01*
X588264Y-152763D01*
X597434D01*
G01X606419Y-153346D02*
X614279Y-135263D01*
G01X627849Y-152763D02*
Y-135263D01*
X625229Y-138763D01*
G01Y-152763D02*
X630469D01*
G01X645349D02*
Y-135263D01*
X642729Y-138763D01*
G01Y-152763D02*
X647969D01*
G01X658919Y-153346D02*
X666779Y-135263D01*
G01X676201Y-138180D02*
X677511Y-136430D01*
X679039Y-135555D01*
X680786Y-135263D01*
X682969Y-135846D01*
X684497Y-137305D01*
X684934Y-139054D01*
X684716Y-140805D01*
X683842Y-142263D01*
X679476Y-145180D01*
X677511Y-147221D01*
X676201Y-150139D01*
X675764Y-152763D01*
X684934D01*
G01X697849Y-135263D02*
X696102Y-135846D01*
X694792Y-137305D01*
X693919Y-139054D01*
X693264Y-141388D01*
X693046Y-144013D01*
X693264Y-146638D01*
X693919Y-148972D01*
X694792Y-150722D01*
X696102Y-152180D01*
X697849Y-152763D01*
X699595Y-152180D01*
X700906Y-150722D01*
X701779Y-148972D01*
X702434Y-146638D01*
X702652Y-144013D01*
X702434Y-141388D01*
X701779Y-139054D01*
X700906Y-137305D01*
X699595Y-135846D01*
X697849Y-135263D01*
G01X715349Y-152763D02*
Y-135263D01*
X712729Y-138763D01*
G01Y-152763D02*
X717969D01*
G01X728046Y-150139D02*
X729355Y-151597D01*
X730884Y-152471D01*
X732849Y-152763D01*
X734814Y-152180D01*
X736342Y-151013D01*
X737434Y-148972D01*
X737652Y-146638D01*
X737216Y-144305D01*
X736124Y-142846D01*
X734595Y-141680D01*
X733067Y-141388D01*
X731539Y-141680D01*
X729574Y-142846D01*
X730229Y-135263D01*
X736124D01*
G01X623046Y-107763D02*
Y-90263D01*
X627412D01*
X629159Y-91138D01*
X630469Y-92305D01*
X631561Y-94054D01*
X632434Y-96097D01*
X632652Y-99013D01*
X632434Y-101930D01*
X631561Y-103972D01*
X630469Y-105722D01*
X629159Y-106888D01*
X627412Y-107763D01*
X623046D01*
G01X649279D02*
Y-96097D01*
G01Y-98138D02*
X648406Y-96972D01*
X647095Y-96388D01*
X645567Y-96097D01*
X644039Y-96680D01*
X642729Y-97846D01*
X641855Y-99596D01*
X641419Y-101930D01*
X641855Y-104263D01*
X642729Y-106013D01*
X644039Y-107180D01*
X645567Y-107763D01*
X647095Y-107471D01*
X648406Y-106597D01*
X649279Y-105430D01*
G01X662849Y-90263D02*
Y-107763D01*
G01X659792Y-96097D02*
X665906D01*
G01X677074Y-99888D02*
X684061D01*
X683406Y-97846D01*
X682314Y-96680D01*
X680786Y-96097D01*
X679257Y-96388D01*
X677947Y-97263D01*
X677074Y-99305D01*
X676637Y-101055D01*
Y-102805D01*
X677074Y-104555D01*
X678166Y-106305D01*
X679476Y-107471D01*
X681004Y-107763D01*
X682532Y-107180D01*
X684061Y-105430D01*
G01X100975Y1779000D02*
Y1781500D01*
G01X99225D02*
Y1779000D01*
G01Y1780250D02*
X100975D01*
G01X97000Y1779000D02*
Y1781500D01*
X97500Y1781000D01*
G01Y1779000D02*
X96500D01*
G01X93900Y1781500D02*
X94233Y1781417D01*
X94483Y1781208D01*
X94650Y1780958D01*
X94775Y1780625D01*
X94817Y1780250D01*
X94775Y1779875D01*
X94650Y1779542D01*
X94483Y1779292D01*
X94233Y1779083D01*
X93900Y1779000D01*
X93567Y1779083D01*
X93317Y1779292D01*
X93150Y1779542D01*
X93025Y1779875D01*
X92983Y1780250D01*
X93025Y1780625D01*
X93150Y1780958D01*
X93317Y1781208D01*
X93567Y1781417D01*
X93900Y1781500D01*
G01X105425Y1846000D02*
Y1848500D01*
G01X103675D02*
Y1846000D01*
G01Y1847250D02*
X105425D01*
G01X102158Y1846292D02*
X101867Y1846083D01*
X101533Y1846000D01*
X101200Y1846083D01*
X100908Y1846333D01*
X100700Y1846708D01*
X100617Y1847083D01*
Y1847542D01*
X100700Y1847917D01*
X100908Y1848250D01*
X101158Y1848417D01*
X101450Y1848500D01*
X101783Y1848417D01*
X102033Y1848250D01*
X102200Y1848000D01*
X102283Y1847667D01*
X102200Y1847375D01*
X101992Y1847083D01*
X101742Y1846917D01*
X101450Y1846875D01*
X101117Y1846958D01*
X100867Y1847167D01*
X100617Y1847542D01*
G01X183475Y1352000D02*
Y1354500D01*
G01X181725D02*
Y1352000D01*
G01Y1353250D02*
X183475D01*
G01X179500Y1352000D02*
Y1354500D01*
X180000Y1354000D01*
G01Y1352000D02*
X179000D01*
G01X177317Y1352500D02*
X177067Y1352208D01*
X176733Y1352042D01*
X176358Y1352000D01*
X176025Y1352042D01*
X175692Y1352250D01*
X175483Y1352500D01*
X175442Y1352750D01*
X175525Y1353042D01*
X175817Y1353250D01*
X176108Y1353333D01*
X176483D01*
G01X176108D02*
X175858Y1353458D01*
X175650Y1353667D01*
X175567Y1353917D01*
X175650Y1354167D01*
X175858Y1354375D01*
X176233Y1354500D01*
X176608Y1354458D01*
X176983Y1354292D01*
G01X176876Y1770801D02*
Y1773301D01*
G01X175126D02*
Y1770801D01*
G01Y1772051D02*
X176876D01*
G01X172901Y1770801D02*
Y1773301D01*
X173401Y1772801D01*
G01Y1770801D02*
X172401D01*
G01X170593Y1772884D02*
X170343Y1773134D01*
X170051Y1773259D01*
X169718Y1773301D01*
X169301Y1773218D01*
X169009Y1773009D01*
X168926Y1772759D01*
X168968Y1772509D01*
X169134Y1772301D01*
X169968Y1771884D01*
X170343Y1771593D01*
X170593Y1771176D01*
X170676Y1770801D01*
X168926D01*
G01X166076Y1847700D02*
Y1850200D01*
G01X164326D02*
Y1847700D01*
G01Y1848950D02*
X166076D01*
G01X162101Y1847700D02*
Y1850200D01*
X162601Y1849700D01*
G01Y1847700D02*
X161601D01*
G01X159001D02*
Y1850200D01*
X159501Y1849700D01*
G01Y1847700D02*
X158501D01*
M02*
